(kicad_pcb
	(version 20260206)
	(generator "pcbnew")
	(generator_version "10.0")
	(general
		(thickness 1.6)
		(legacy_teardrops no)
	)
	(paper "A4")
	(title_block
		(title "03242023_DA0F0TMBIJ0_F0T_Motherboard_J_brd_V01_OCP.brd")
		(comment 1 "Grand Teton / footprints 2177-2183 of 6105")
	)
	(layers
		(0 "F.Cu" signal "TOP")
		(4 "In1.Cu" signal "GND")
		(6 "In2.Cu" signal "IN1")
		(8 "In3.Cu" signal "GND1")
		(10 "In4.Cu" signal "IN2")
		(12 "In5.Cu" signal "GND2")
		(14 "In6.Cu" signal "IN3")
		(16 "In7.Cu" signal "GND3")
		(18 "In8.Cu" signal "VCC")
		(20 "In9.Cu" signal "VCC1")
		(22 "In10.Cu" signal "GND4")
		(24 "In11.Cu" signal "IN4")
		(26 "In12.Cu" signal "GND5")
		(28 "In13.Cu" signal "IN5")
		(30 "In14.Cu" signal "GND6")
		(32 "In15.Cu" signal "IN6")
		(34 "In16.Cu" signal "GND7")
		(2 "B.Cu" signal "BOTTOM")
		(9 "F.Adhes" user "F.Adhesive")
		(11 "B.Adhes" user "B.Adhesive")
		(13 "F.Paste" user "Package Geometry/Pastemask Top")
		(15 "B.Paste" user "Package Geometry/Pastemask Bottom")
		(5 "F.SilkS" user "Ref Des/Silkscreen Top")
		(7 "B.SilkS" user "Ref Des/Silkscreen Bottom")
		(1 "F.Mask" user "Board Geometry/Soldermask Top")
		(3 "B.Mask" user "Board Geometry/Soldermask Bottom")
		(17 "Dwgs.User" user "User.Drawings")
		(19 "Cmts.User" user "User.Comments")
		(21 "Eco1.User" user "User.Eco1")
		(23 "Eco2.User" user "User.Eco2")
		(25 "Edge.Cuts" user "Board Geometry/Outline")
		(27 "Margin" user)
		(31 "F.CrtYd" user "Package Geometry/Place Bound Top")
		(29 "B.CrtYd" user "Package Geometry/Place Bound Bottom")
		(35 "F.Fab" user "Ref Des/Assembly Top")
		(33 "B.Fab" user "Ref Des/Assembly Bottom")
	)
	(footprint ""
		(layer "F.Cu")
		(at 378.5616 -107.183428)
		(property "Reference" "C1664"
			(at 0 0 0)
			(layer "F.SilkS")
			(hide yes)
			(effects
				(font
					(size 1.27 1.27)
				)
			)
		)
		(property "Value" ""
			(at 0 0 0)
			(layer "F.Fab")
			(effects
				(font
					(size 1.27 1.27)
				)
			)
		)
		(duplicate_pad_numbers_are_jumpers no)
		(fp_line
			(start -0.7874 -0.4064)
			(end 0.7874 -0.4064)
			(stroke
				(width 0.1524)
				(type default)
			)
			(layer "F.SilkS")
		)
		(fp_line
			(start -0.7874 0.4064)
			(end -0.7874 -0.4064)
			(stroke
				(width 0.1524)
				(type default)
			)
			(layer "F.SilkS")
		)
		(fp_line
			(start 0.7874 -0.4064)
			(end 0.7874 0.4064)
			(stroke
				(width 0.1524)
				(type default)
			)
			(layer "F.SilkS")
		)
		(fp_line
			(start 0.7874 0.4064)
			(end -0.7874 0.4064)
			(stroke
				(width 0.1524)
				(type default)
			)
			(layer "F.SilkS")
		)
		(fp_line
			(start -0.67945 -0.305054)
			(end -0.12065 -0.305054)
			(stroke
				(width 0.1)
				(type default)
			)
			(layer "F.Fab")
		)
		(fp_line
			(start -0.67945 0.3048)
			(end -0.67945 -0.305054)
			(stroke
				(width 0.1)
				(type default)
			)
			(layer "F.Fab")
		)
		(fp_line
			(start -0.12065 -0.305054)
			(end -0.12065 -0.2794)
			(stroke
				(width 0.1)
				(type default)
			)
			(layer "F.Fab")
		)
		(fp_line
			(start -0.12065 -0.2794)
			(end 0.12065 -0.2794)
			(stroke
				(width 0.1)
				(type default)
			)
			(layer "F.Fab")
		)
		(fp_line
			(start -0.12065 0.2794)
			(end -0.12065 0.3048)
			(stroke
				(width 0.1)
				(type default)
			)
			(layer "F.Fab")
		)
		(fp_line
			(start -0.12065 0.3048)
			(end -0.67945 0.3048)
			(stroke
				(width 0.1)
				(type default)
			)
			(layer "F.Fab")
		)
		(fp_line
			(start 0.120396 0.2794)
			(end -0.12065 0.2794)
			(stroke
				(width 0.1)
				(type default)
			)
			(layer "F.Fab")
		)
		(fp_line
			(start 0.120396 0.3048)
			(end 0.120396 0.2794)
			(stroke
				(width 0.1)
				(type default)
			)
			(layer "F.Fab")
		)
		(fp_line
			(start 0.12065 -0.3048)
			(end 0.67945 -0.3048)
			(stroke
				(width 0.1)
				(type default)
			)
			(layer "F.Fab")
		)
		(fp_line
			(start 0.12065 -0.2794)
			(end 0.12065 -0.3048)
			(stroke
				(width 0.1)
				(type default)
			)
			(layer "F.Fab")
		)
		(fp_line
			(start 0.67945 -0.3048)
			(end 0.67945 0.3048)
			(stroke
				(width 0.1)
				(type default)
			)
			(layer "F.Fab")
		)
		(fp_line
			(start 0.67945 0.3048)
			(end 0.120396 0.3048)
			(stroke
				(width 0.1)
				(type default)
			)
			(layer "F.Fab")
		)
		(pad "1" smd circle
			(at -0.40005 0)
			(size 0 0)
			(layers "F.Cu" "F.Mask" "F.Paste")
			(net "P0V7_JTAG_VREF_2")
		)
		(pad "2" smd circle
			(at 0.40005 0)
			(size 0 0)
			(layers "F.Cu" "F.Mask" "F.Paste")
			(net "GND")
		)
	)
	(footprint ""
		(layer "F.Cu")
		(at 352.283014 -251.375418 90)
		(property "Reference" "C1014"
			(at 0 0 90)
			(layer "F.SilkS")
			(hide yes)
			(effects
				(font
					(size 1.27 1.27)
				)
			)
		)
		(property "Value" ""
			(at 0 0 90)
			(layer "F.Fab")
			(effects
				(font
					(size 1.27 1.27)
				)
			)
		)
		(duplicate_pad_numbers_are_jumpers no)
		(fp_line
			(start 0.7874 -0.4064)
			(end 0.7874 0.4064)
			(stroke
				(width 0.1524)
				(type default)
			)
			(layer "F.SilkS")
		)
		(fp_line
			(start -0.7874 -0.4064)
			(end 0.7874 -0.4064)
			(stroke
				(width 0.1524)
				(type default)
			)
			(layer "F.SilkS")
		)
		(fp_line
			(start 0.7874 0.4064)
			(end -0.7874 0.4064)
			(stroke
				(width 0.1524)
				(type default)
			)
			(layer "F.SilkS")
		)
		(fp_line
			(start -0.7874 0.4064)
			(end -0.7874 -0.4064)
			(stroke
				(width 0.1524)
				(type default)
			)
			(layer "F.SilkS")
		)
		(fp_line
			(start -0.12065 -0.305054)
			(end -0.12065 -0.2794)
			(stroke
				(width 0.1)
				(type default)
			)
			(layer "F.Fab")
		)
		(fp_line
			(start -0.67945 -0.305054)
			(end -0.12065 -0.305054)
			(stroke
				(width 0.1)
				(type default)
			)
			(layer "F.Fab")
		)
		(fp_line
			(start 0.67945 -0.3048)
			(end 0.67945 0.3048)
			(stroke
				(width 0.1)
				(type default)
			)
			(layer "F.Fab")
		)
		(fp_line
			(start 0.12065 -0.3048)
			(end 0.67945 -0.3048)
			(stroke
				(width 0.1)
				(type default)
			)
			(layer "F.Fab")
		)
		(fp_line
			(start 0.12065 -0.2794)
			(end 0.12065 -0.3048)
			(stroke
				(width 0.1)
				(type default)
			)
			(layer "F.Fab")
		)
		(fp_line
			(start -0.12065 -0.2794)
			(end 0.12065 -0.2794)
			(stroke
				(width 0.1)
				(type default)
			)
			(layer "F.Fab")
		)
		(fp_line
			(start 0.120396 0.2794)
			(end -0.12065 0.2794)
			(stroke
				(width 0.1)
				(type default)
			)
			(layer "F.Fab")
		)
		(fp_line
			(start -0.12065 0.2794)
			(end -0.12065 0.3048)
			(stroke
				(width 0.1)
				(type default)
			)
			(layer "F.Fab")
		)
		(fp_line
			(start 0.67945 0.3048)
			(end 0.120396 0.3048)
			(stroke
				(width 0.1)
				(type default)
			)
			(layer "F.Fab")
		)
		(fp_line
			(start 0.120396 0.3048)
			(end 0.120396 0.2794)
			(stroke
				(width 0.1)
				(type default)
			)
			(layer "F.Fab")
		)
		(fp_line
			(start -0.12065 0.3048)
			(end -0.67945 0.3048)
			(stroke
				(width 0.1)
				(type default)
			)
			(layer "F.Fab")
		)
		(fp_line
			(start -0.67945 0.3048)
			(end -0.67945 -0.305054)
			(stroke
				(width 0.1)
				(type default)
			)
			(layer "F.Fab")
		)
		(pad "1" smd circle
			(at -0.40005 0 90)
			(size 0 0)
			(layers "F.Cu" "F.Mask" "F.Paste")
			(net "PVCCIN_CPU0")
		)
		(pad "2" smd circle
			(at 0.40005 0 90)
			(size 0 0)
			(layers "F.Cu" "F.Mask" "F.Paste")
			(net "GND")
		)
	)
	(footprint ""
		(layer "F.Cu")
		(at 367.44783 -256.654046 -90)
		(property "Reference" "C996"
			(at 0 0 270)
			(layer "F.SilkS")
			(hide yes)
			(effects
				(font
					(size 1.27 1.27)
				)
			)
		)
		(property "Value" ""
			(at 0 0 270)
			(layer "F.Fab")
			(effects
				(font
					(size 1.27 1.27)
				)
			)
		)
		(duplicate_pad_numbers_are_jumpers no)
		(fp_line
			(start -0.7874 0.4064)
			(end -0.7874 -0.4064)
			(stroke
				(width 0.1524)
				(type default)
			)
			(layer "F.SilkS")
		)
		(fp_line
			(start 0.7874 0.4064)
			(end -0.7874 0.4064)
			(stroke
				(width 0.1524)
				(type default)
			)
			(layer "F.SilkS")
		)
		(fp_line
			(start -0.7874 -0.4064)
			(end 0.7874 -0.4064)
			(stroke
				(width 0.1524)
				(type default)
			)
			(layer "F.SilkS")
		)
		(fp_line
			(start 0.7874 -0.4064)
			(end 0.7874 0.4064)
			(stroke
				(width 0.1524)
				(type default)
			)
			(layer "F.SilkS")
		)
		(fp_line
			(start -0.67945 0.3048)
			(end -0.67945 -0.305054)
			(stroke
				(width 0.1)
				(type default)
			)
			(layer "F.Fab")
		)
		(fp_line
			(start -0.12065 0.3048)
			(end -0.67945 0.3048)
			(stroke
				(width 0.1)
				(type default)
			)
			(layer "F.Fab")
		)
		(fp_line
			(start 0.120396 0.3048)
			(end 0.120396 0.2794)
			(stroke
				(width 0.1)
				(type default)
			)
			(layer "F.Fab")
		)
		(fp_line
			(start 0.67945 0.3048)
			(end 0.120396 0.3048)
			(stroke
				(width 0.1)
				(type default)
			)
			(layer "F.Fab")
		)
		(fp_line
			(start -0.12065 0.2794)
			(end -0.12065 0.3048)
			(stroke
				(width 0.1)
				(type default)
			)
			(layer "F.Fab")
		)
		(fp_line
			(start 0.120396 0.2794)
			(end -0.12065 0.2794)
			(stroke
				(width 0.1)
				(type default)
			)
			(layer "F.Fab")
		)
		(fp_line
			(start -0.12065 -0.2794)
			(end 0.12065 -0.2794)
			(stroke
				(width 0.1)
				(type default)
			)
			(layer "F.Fab")
		)
		(fp_line
			(start 0.12065 -0.2794)
			(end 0.12065 -0.3048)
			(stroke
				(width 0.1)
				(type default)
			)
			(layer "F.Fab")
		)
		(fp_line
			(start 0.12065 -0.3048)
			(end 0.67945 -0.3048)
			(stroke
				(width 0.1)
				(type default)
			)
			(layer "F.Fab")
		)
		(fp_line
			(start 0.67945 -0.3048)
			(end 0.67945 0.3048)
			(stroke
				(width 0.1)
				(type default)
			)
			(layer "F.Fab")
		)
		(fp_line
			(start -0.67945 -0.305054)
			(end -0.12065 -0.305054)
			(stroke
				(width 0.1)
				(type default)
			)
			(layer "F.Fab")
		)
		(fp_line
			(start -0.12065 -0.305054)
			(end -0.12065 -0.2794)
			(stroke
				(width 0.1)
				(type default)
			)
			(layer "F.Fab")
		)
		(pad "1" smd circle
			(at -0.40005 0 270)
			(size 0 0)
			(layers "F.Cu" "F.Mask" "F.Paste")
			(net "PVCCIN_CPU0")
		)
		(pad "2" smd circle
			(at 0.40005 0 270)
			(size 0 0)
			(layers "F.Cu" "F.Mask" "F.Paste")
			(net "GND")
		)
	)
	(footprint ""
		(layer "F.Cu")
		(at 393.880086 -251.76988)
		(property "Reference" "H19"
			(at 4.645914 -4.708398 0)
			(unlocked yes)
			(layer "F.SilkS")
			(effects
				(font
					(size 0.7874 0.5842)
					(thickness 0.1524)
				)
				(justify left)
			)
		)
		(property "Value" ""
			(at 0 0 0)
			(layer "F.Fab")
			(effects
				(font
					(size 1.27 1.27)
				)
			)
		)
		(duplicate_pad_numbers_are_jumpers no)
		(fp_circle
			(center 0 0)
			(end 2.5273 0)
			(stroke
				(width 0.1524)
				(type default)
			)
			(fill no)
			(layer "F.SilkS")
		)
		(fp_circle
			(center 0 0)
			(end 2.5273 0)
			(stroke
				(width 0.1524)
				(type default)
			)
			(fill no)
			(layer "B.SilkS")
		)
		(fp_circle
			(center 0 0)
			(end 2.5273 0)
			(stroke
				(width 0.1)
				(type default)
			)
			(fill no)
			(layer "B.Fab")
		)
		(fp_circle
			(center 0 0)
			(end 2.5273 0)
			(stroke
				(width 0.1)
				(type default)
			)
			(fill no)
			(layer "F.Fab")
		)
		(pad "" np_thru_hole circle
			(at 0 0)
			(size 3.429 3.429)
			(drill 3.429)
			(layers "*.Cu" "*.Mask")
			(clearance 0.381)
			(thermal_gap 0.381)
		)
	)
	(footprint ""
		(layer "F.Cu")
		(at 55.978298 -353.643946 -90)
		(property "Reference" "PC398_P1_2"
			(at 0 0 270)
			(layer "F.SilkS")
			(hide yes)
			(effects
				(font
					(size 1.27 1.27)
				)
			)
		)
		(property "Value" ""
			(at 0 0 270)
			(layer "F.Fab")
			(effects
				(font
					(size 1.27 1.27)
				)
			)
		)
		(duplicate_pad_numbers_are_jumpers no)
		(fp_line
			(start -0.7874 0.4064)
			(end -0.7874 -0.4064)
			(stroke
				(width 0.1524)
				(type default)
			)
			(layer "F.SilkS")
		)
		(fp_line
			(start 0.7874 0.4064)
			(end -0.7874 0.4064)
			(stroke
				(width 0.1524)
				(type default)
			)
			(layer "F.SilkS")
		)
		(fp_line
			(start -0.7874 -0.4064)
			(end 0.7874 -0.4064)
			(stroke
				(width 0.1524)
				(type default)
			)
			(layer "F.SilkS")
		)
		(fp_line
			(start 0.7874 -0.4064)
			(end 0.7874 0.4064)
			(stroke
				(width 0.1524)
				(type default)
			)
			(layer "F.SilkS")
		)
		(fp_line
			(start -0.67945 0.3048)
			(end -0.67945 -0.305054)
			(stroke
				(width 0.1)
				(type default)
			)
			(layer "F.Fab")
		)
		(fp_line
			(start -0.12065 0.3048)
			(end -0.67945 0.3048)
			(stroke
				(width 0.1)
				(type default)
			)
			(layer "F.Fab")
		)
		(fp_line
			(start 0.120396 0.3048)
			(end 0.120396 0.2794)
			(stroke
				(width 0.1)
				(type default)
			)
			(layer "F.Fab")
		)
		(fp_line
			(start 0.67945 0.3048)
			(end 0.120396 0.3048)
			(stroke
				(width 0.1)
				(type default)
			)
			(layer "F.Fab")
		)
		(fp_line
			(start -0.12065 0.2794)
			(end -0.12065 0.3048)
			(stroke
				(width 0.1)
				(type default)
			)
			(layer "F.Fab")
		)
		(fp_line
			(start 0.120396 0.2794)
			(end -0.12065 0.2794)
			(stroke
				(width 0.1)
				(type default)
			)
			(layer "F.Fab")
		)
		(fp_line
			(start -0.12065 -0.2794)
			(end 0.12065 -0.2794)
			(stroke
				(width 0.1)
				(type default)
			)
			(layer "F.Fab")
		)
		(fp_line
			(start 0.12065 -0.2794)
			(end 0.12065 -0.3048)
			(stroke
				(width 0.1)
				(type default)
			)
			(layer "F.Fab")
		)
		(fp_line
			(start 0.12065 -0.3048)
			(end 0.67945 -0.3048)
			(stroke
				(width 0.1)
				(type default)
			)
			(layer "F.Fab")
		)
		(fp_line
			(start 0.67945 -0.3048)
			(end 0.67945 0.3048)
			(stroke
				(width 0.1)
				(type default)
			)
			(layer "F.Fab")
		)
		(fp_line
			(start -0.67945 -0.305054)
			(end -0.12065 -0.305054)
			(stroke
				(width 0.1)
				(type default)
			)
			(layer "F.Fab")
		)
		(fp_line
			(start -0.12065 -0.305054)
			(end -0.12065 -0.2794)
			(stroke
				(width 0.1)
				(type default)
			)
			(layer "F.Fab")
		)
		(pad "1" smd circle
			(at -0.40005 0 270)
			(size 0 0)
			(layers "F.Cu" "F.Mask" "F.Paste")
			(net "SW_P12V_PVCCFA_EHV_FIVRA_CPU1_L")
		)
		(pad "2" smd circle
			(at 0.40005 0 270)
			(size 0 0)
			(layers "F.Cu" "F.Mask" "F.Paste")
			(net "GND")
		)
	)
	(footprint ""
		(layer "F.Cu")
		(at 302.895 -421.49395 90)
		(property "Reference" "R4119"
			(at 0 0 90)
			(layer "F.SilkS")
			(hide yes)
			(effects
				(font
					(size 1.27 1.27)
				)
			)
		)
		(property "Value" ""
			(at 0 0 90)
			(layer "F.Fab")
			(effects
				(font
					(size 1.27 1.27)
				)
			)
		)
		(duplicate_pad_numbers_are_jumpers no)
		(fp_line
			(start 0.7874 -0.4064)
			(end 0.7874 0.4064)
			(stroke
				(width 0.1524)
				(type default)
			)
			(layer "F.SilkS")
		)
		(fp_line
			(start -0.7874 -0.4064)
			(end 0.7874 -0.4064)
			(stroke
				(width 0.1524)
				(type default)
			)
			(layer "F.SilkS")
		)
		(fp_line
			(start 0.7874 0.4064)
			(end -0.7874 0.4064)
			(stroke
				(width 0.1524)
				(type default)
			)
			(layer "F.SilkS")
		)
		(fp_line
			(start -0.7874 0.4064)
			(end -0.7874 -0.4064)
			(stroke
				(width 0.1524)
				(type default)
			)
			(layer "F.SilkS")
		)
		(fp_line
			(start -0.12065 -0.305054)
			(end -0.12065 -0.2794)
			(stroke
				(width 0.1)
				(type default)
			)
			(layer "F.Fab")
		)
		(fp_line
			(start -0.67945 -0.305054)
			(end -0.12065 -0.305054)
			(stroke
				(width 0.1)
				(type default)
			)
			(layer "F.Fab")
		)
		(fp_line
			(start 0.67945 -0.3048)
			(end 0.67945 0.3048)
			(stroke
				(width 0.1)
				(type default)
			)
			(layer "F.Fab")
		)
		(fp_line
			(start 0.12065 -0.3048)
			(end 0.67945 -0.3048)
			(stroke
				(width 0.1)
				(type default)
			)
			(layer "F.Fab")
		)
		(fp_line
			(start 0.12065 -0.2794)
			(end 0.12065 -0.3048)
			(stroke
				(width 0.1)
				(type default)
			)
			(layer "F.Fab")
		)
		(fp_line
			(start -0.12065 -0.2794)
			(end 0.12065 -0.2794)
			(stroke
				(width 0.1)
				(type default)
			)
			(layer "F.Fab")
		)
		(fp_line
			(start 0.120396 0.2794)
			(end -0.12065 0.2794)
			(stroke
				(width 0.1)
				(type default)
			)
			(layer "F.Fab")
		)
		(fp_line
			(start -0.12065 0.2794)
			(end -0.12065 0.3048)
			(stroke
				(width 0.1)
				(type default)
			)
			(layer "F.Fab")
		)
		(fp_line
			(start 0.67945 0.3048)
			(end 0.120396 0.3048)
			(stroke
				(width 0.1)
				(type default)
			)
			(layer "F.Fab")
		)
		(fp_line
			(start 0.120396 0.3048)
			(end 0.120396 0.2794)
			(stroke
				(width 0.1)
				(type default)
			)
			(layer "F.Fab")
		)
		(fp_line
			(start -0.12065 0.3048)
			(end -0.67945 0.3048)
			(stroke
				(width 0.1)
				(type default)
			)
			(layer "F.Fab")
		)
		(fp_line
			(start -0.67945 0.3048)
			(end -0.67945 -0.305054)
			(stroke
				(width 0.1)
				(type default)
			)
			(layer "F.Fab")
		)
		(pad "1" smd circle
			(at -0.40005 0 90)
			(size 0 0)
			(layers "F.Cu" "F.Mask" "F.Paste")
			(net "P3V3_AUX")
		)
		(pad "2" smd circle
			(at 0.40005 0 90)
			(size 0 0)
			(layers "F.Cu" "F.Mask" "F.Paste")
			(net "GPU_3V3IO_RSVD0_FFU")
		)
	)
	(footprint ""
		(layer "F.Cu")
		(at 307.95087 -425.186602)
		(property "Reference" "C2283"
			(at 0 0 0)
			(layer "F.SilkS")
			(hide yes)
			(effects
				(font
					(size 1.27 1.27)
				)
			)
		)
		(property "Value" ""
			(at 0 0 0)
			(layer "F.Fab")
			(effects
				(font
					(size 1.27 1.27)
				)
			)
		)
		(duplicate_pad_numbers_are_jumpers no)
		(fp_line
			(start -0.7874 -0.4064)
			(end 0.7874 -0.4064)
			(stroke
				(width 0.1524)
				(type default)
			)
			(layer "F.SilkS")
		)
		(fp_line
			(start -0.7874 0.4064)
			(end -0.7874 -0.4064)
			(stroke
				(width 0.1524)
				(type default)
			)
			(layer "F.SilkS")
		)
		(fp_line
			(start 0.7874 -0.4064)
			(end 0.7874 0.4064)
			(stroke
				(width 0.1524)
				(type default)
			)
			(layer "F.SilkS")
		)
		(fp_line
			(start 0.7874 0.4064)
			(end -0.7874 0.4064)
			(stroke
				(width 0.1524)
				(type default)
			)
			(layer "F.SilkS")
		)
		(fp_line
			(start -0.67945 -0.305054)
			(end -0.12065 -0.305054)
			(stroke
				(width 0.1)
				(type default)
			)
			(layer "F.Fab")
		)
		(fp_line
			(start -0.67945 0.3048)
			(end -0.67945 -0.305054)
			(stroke
				(width 0.1)
				(type default)
			)
			(layer "F.Fab")
		)
		(fp_line
			(start -0.12065 -0.305054)
			(end -0.12065 -0.2794)
			(stroke
				(width 0.1)
				(type default)
			)
			(layer "F.Fab")
		)
		(fp_line
			(start -0.12065 -0.2794)
			(end 0.12065 -0.2794)
			(stroke
				(width 0.1)
				(type default)
			)
			(layer "F.Fab")
		)
		(fp_line
			(start -0.12065 0.2794)
			(end -0.12065 0.3048)
			(stroke
				(width 0.1)
				(type default)
			)
			(layer "F.Fab")
		)
		(fp_line
			(start -0.12065 0.3048)
			(end -0.67945 0.3048)
			(stroke
				(width 0.1)
				(type default)
			)
			(layer "F.Fab")
		)
		(fp_line
			(start 0.120396 0.2794)
			(end -0.12065 0.2794)
			(stroke
				(width 0.1)
				(type default)
			)
			(layer "F.Fab")
		)
		(fp_line
			(start 0.120396 0.3048)
			(end 0.120396 0.2794)
			(stroke
				(width 0.1)
				(type default)
			)
			(layer "F.Fab")
		)
		(fp_line
			(start 0.12065 -0.3048)
			(end 0.67945 -0.3048)
			(stroke
				(width 0.1)
				(type default)
			)
			(layer "F.Fab")
		)
		(fp_line
			(start 0.12065 -0.2794)
			(end 0.12065 -0.3048)
			(stroke
				(width 0.1)
				(type default)
			)
			(layer "F.Fab")
		)
		(fp_line
			(start 0.67945 -0.3048)
			(end 0.67945 0.3048)
			(stroke
				(width 0.1)
				(type default)
			)
			(layer "F.Fab")
		)
		(fp_line
			(start 0.67945 0.3048)
			(end 0.120396 0.3048)
			(stroke
				(width 0.1)
				(type default)
			)
			(layer "F.Fab")
		)
		(pad "1" smd circle
			(at -0.40005 0)
			(size 0 0)
			(layers "F.Cu" "F.Mask" "F.Paste")
			(net "P3V3_AUX")
		)
		(pad "2" smd circle
			(at 0.40005 0)
			(size 0 0)
			(layers "F.Cu" "F.Mask" "F.Paste")
			(net "GND")
		)
	)
)
